(kicad_pcb
	(version 20260206)
	(generator "pcbnew")
	(generator_version "10.0")
	(general
		(thickness 1.6)
		(legacy_teardrops no)
	)
	(paper "A4")
	(title_block
		(title "04192023_DAF0TMB3IC0_F0TG_MB_C_brd_V02_OCP.brd")
		(comment 1 "Grand Teton / footprint 2783 of 8354 (U26), pads 867-975 of 6102")
	)
	(layers
		(0 "F.Cu" signal "TOP")
		(4 "In1.Cu" signal "GND")
		(6 "In2.Cu" signal "IN1")
		(8 "In3.Cu" signal "GND1")
		(10 "In4.Cu" signal "IN2")
		(12 "In5.Cu" signal "GND2")
		(14 "In6.Cu" signal "IN3")
		(16 "In7.Cu" signal "GND3")
		(18 "In8.Cu" signal "VCC")
		(20 "In9.Cu" signal "VCC1")
		(22 "In10.Cu" signal "GND4")
		(24 "In11.Cu" signal "IN4")
		(26 "In12.Cu" signal "GND5")
		(28 "In13.Cu" signal "IN5")
		(30 "In14.Cu" signal "GND6")
		(32 "In15.Cu" signal "IN6")
		(34 "In16.Cu" signal "GND7")
		(2 "B.Cu" signal "BOTTOM")
		(9 "F.Adhes" user "F.Adhesive")
		(11 "B.Adhes" user "B.Adhesive")
		(13 "F.Paste" user "Package Geometry/Pastemask Top")
		(15 "B.Paste" user "Package Geometry/Pastemask Bottom")
		(5 "F.SilkS" user "Ref Des/Silkscreen Top")
		(7 "B.SilkS" user "Ref Des/Silkscreen Bottom")
		(1 "F.Mask" user "Board Geometry/Soldermask Top")
		(3 "B.Mask" user "Board Geometry/Soldermask Bottom")
		(17 "Dwgs.User" user "User.Drawings")
		(19 "Cmts.User" user "User.Comments")
		(21 "Eco1.User" user "User.Eco1")
		(23 "Eco2.User" user "User.Eco2")
		(25 "Edge.Cuts" user "Board Geometry/Outline")
		(27 "Margin" user)
		(31 "F.CrtYd" user "Package Geometry/Place Bound Top")
		(29 "B.CrtYd" user "Package Geometry/Place Bound Bottom")
		(35 "F.Fab" user "Ref Des/Assembly Top")
		(33 "B.Fab" user "Ref Des/Assembly Bottom")
	)
	(footprint ""
		(layer "F.Cu")
		(at 111.927894 -258.880356 180)
		(property "Reference" "U26"
			(at -45.05579 -61.794136 0)
			(unlocked yes)
			(layer "F.SilkS")
			(effects
				(font
					(size 0.7874 0.5842)
					(thickness 0.1524)
				)
			)
		)
		(property "Value" ""
			(at 0 0 180)
			(layer "F.Fab")
			(effects
				(font
					(size 1.27 1.27)
				)
			)
		)
		(duplicate_pad_numbers_are_jumpers no)
		(pad "AM14" smd circle
			(at -22.409912 -11.700002 180)
			(size 0.450088 0.450088)
			(layers "F.Cu" "F.Mask" "F.Paste")
			(net "M_H_CPU1_SA_DQS_DN<9>")
		)
		(pad "AM15" smd circle
			(at -21.470112 -11.700002 180)
			(size 0.450088 0.450088)
			(layers "F.Cu" "F.Mask" "F.Paste")
			(net "GND")
		)
		(pad "AM16" smd circle
			(at -20.530058 -11.700002 180)
			(size 0.450088 0.450088)
			(layers "F.Cu" "F.Mask" "F.Paste")
			(net "M_J_CPU1_SA_DQS_DN<4>")
		)
		(pad "AM17" smd circle
			(at -19.590004 -11.700002 180)
			(size 0.450088 0.450088)
			(layers "F.Cu" "F.Mask" "F.Paste")
			(net "GND")
		)
		(pad "AM18" smd circle
			(at -18.64995 -11.700002 180)
			(size 0.450088 0.450088)
			(layers "F.Cu" "F.Mask" "F.Paste")
			(net "M_J_CPU1_SA_DQS_DN<9>")
		)
		(pad "AM19" smd circle
			(at -17.709896 -11.700002 180)
			(size 0.450088 0.450088)
			(layers "F.Cu" "F.Mask" "F.Paste")
			(net "PVDDCR_SOC_P1")
		)
		(pad "AM20" smd circle
			(at -16.770096 -11.700002 180)
			(size 0.450088 0.450088)
			(layers "F.Cu" "F.Mask" "F.Paste")
			(net "M_I_CPU1_SA_DQS_DN<4>")
		)
		(pad "AM21" smd circle
			(at -15.830042 -11.700002 180)
			(size 0.450088 0.450088)
			(layers "F.Cu" "F.Mask" "F.Paste")
			(net "M_I_CPU1_SA_DQS_DN<9>")
		)
		(pad "AM22" smd circle
			(at -14.889988 -11.700002 180)
			(size 0.450088 0.450088)
			(layers "F.Cu" "F.Mask" "F.Paste")
			(net "PVDDCR_SOC_P1")
		)
		(pad "AM23" smd circle
			(at -13.949934 -11.700002 180)
			(size 0.450088 0.450088)
			(layers "F.Cu" "F.Mask" "F.Paste")
			(net "GND")
		)
		(pad "AM24" smd circle
			(at -13.00988 -11.700002 180)
			(size 0.450088 0.450088)
			(layers "F.Cu" "F.Mask" "F.Paste")
			(net "GND")
		)
		(pad "AM25" smd circle
			(at -12.07008 -11.700002 180)
			(size 0.450088 0.450088)
			(layers "F.Cu" "F.Mask" "F.Paste")
			(net "GND")
		)
		(pad "AM26" smd circle
			(at -11.130026 -11.700002 180)
			(size 0.450088 0.450088)
			(layers "F.Cu" "F.Mask" "F.Paste")
			(net "GND")
		)
		(pad "AM27" smd circle
			(at -10.189972 -11.700002 180)
			(size 0.450088 0.450088)
			(layers "F.Cu" "F.Mask" "F.Paste")
			(net "GND")
		)
		(pad "AM28" smd circle
			(at -9.249918 -11.700002 180)
			(size 0.450088 0.450088)
			(layers "F.Cu" "F.Mask" "F.Paste")
			(net "GND")
		)
		(pad "AM29" smd circle
			(at -8.310118 -11.700002 180)
			(size 0.450088 0.450088)
			(layers "F.Cu" "F.Mask" "F.Paste")
			(net "GND")
		)
		(pad "AM30" smd circle
			(at -7.370064 -11.700002 180)
			(size 0.450088 0.450088)
			(layers "F.Cu" "F.Mask" "F.Paste")
			(net "GND")
		)
		(pad "AM31" smd circle
			(at -6.43001 -11.700002 180)
			(size 0.450088 0.450088)
			(layers "F.Cu" "F.Mask" "F.Paste")
			(net "GND")
		)
		(pad "AM32" smd circle
			(at -5.489956 -11.700002 180)
			(size 0.450088 0.450088)
			(layers "F.Cu" "F.Mask" "F.Paste")
			(net "GND")
		)
		(pad "AM33" smd circle
			(at -4.549902 -11.700002 180)
			(size 0.450088 0.450088)
			(layers "F.Cu" "F.Mask" "F.Paste")
			(net "GND")
		)
		(pad "AM34" smd circle
			(at -3.610102 -11.700002 180)
			(size 0.450088 0.450088)
			(layers "F.Cu" "F.Mask" "F.Paste")
			(net "GND")
		)
		(pad "AM35" smd circle
			(at -2.670048 -11.700002 180)
			(size 0.450088 0.450088)
			(layers "F.Cu" "F.Mask" "F.Paste")
			(net "GMI_CPU0_G1_CPU1_G3_TX_DN<1>")
		)
		(pad "AM36" smd circle
			(at -1.729994 -11.700002 180)
			(size 0.450088 0.450088)
			(layers "F.Cu" "F.Mask" "F.Paste")
			(net "GMI_CPU0_G1_CPU1_G3_TX_DP<1>")
		)
		(pad "AM37" smd circle
			(at -0.78994 -11.700002 180)
			(size 0.450088 0.450088)
			(layers "F.Cu" "F.Mask" "F.Paste")
			(net "GND")
		)
		(pad "AM39" smd circle
			(at 1.089914 -11.700002 180)
			(size 0.450088 0.450088)
			(layers "F.Cu" "F.Mask" "F.Paste")
			(net "GND")
		)
		(pad "AM40" smd circle
			(at 2.029968 -11.700002 180)
			(size 0.450088 0.450088)
			(layers "F.Cu" "F.Mask" "F.Paste")
			(net "P5E_CPU1_G1_TX_DP<1>")
		)
		(pad "AM41" smd circle
			(at 2.970022 -11.700002 180)
			(size 0.450088 0.450088)
			(layers "F.Cu" "F.Mask" "F.Paste")
			(net "P5E_CPU1_G1_TX_DN<1>")
		)
		(pad "AM42" smd circle
			(at 3.910076 -11.700002 180)
			(size 0.450088 0.450088)
			(layers "F.Cu" "F.Mask" "F.Paste")
			(net "GND")
		)
		(pad "AM43" smd circle
			(at 4.849876 -11.700002 180)
			(size 0.450088 0.450088)
			(layers "F.Cu" "F.Mask" "F.Paste")
			(net "GND")
		)
		(pad "AM44" smd circle
			(at 5.78993 -11.700002 180)
			(size 0.450088 0.450088)
			(layers "F.Cu" "F.Mask" "F.Paste")
			(net "GND")
		)
		(pad "AM45" smd circle
			(at 6.729984 -11.700002 180)
			(size 0.450088 0.450088)
			(layers "F.Cu" "F.Mask" "F.Paste")
			(net "GND")
		)
		(pad "AM46" smd circle
			(at 7.670038 -11.700002 180)
			(size 0.450088 0.450088)
			(layers "F.Cu" "F.Mask" "F.Paste")
			(net "GND")
		)
		(pad "AM47" smd circle
			(at 8.610092 -11.700002 180)
			(size 0.450088 0.450088)
			(layers "F.Cu" "F.Mask" "F.Paste")
			(net "GND")
		)
		(pad "AM48" smd circle
			(at 9.549892 -11.700002 180)
			(size 0.450088 0.450088)
			(layers "F.Cu" "F.Mask" "F.Paste")
			(net "GND")
		)
		(pad "AM49" smd circle
			(at 10.489946 -11.700002 180)
			(size 0.450088 0.450088)
			(layers "F.Cu" "F.Mask" "F.Paste")
			(net "GND")
		)
		(pad "AM50" smd circle
			(at 11.43 -11.700002 180)
			(size 0.450088 0.450088)
			(layers "F.Cu" "F.Mask" "F.Paste")
			(net "GND")
		)
		(pad "AM51" smd circle
			(at 12.370054 -11.700002 180)
			(size 0.450088 0.450088)
			(layers "F.Cu" "F.Mask" "F.Paste")
			(net "GND")
		)
		(pad "AM52" smd circle
			(at 13.310108 -11.700002 180)
			(size 0.450088 0.450088)
			(layers "F.Cu" "F.Mask" "F.Paste")
			(net "GND")
		)
		(pad "AM53" smd circle
			(at 14.249908 -11.700002 180)
			(size 0.450088 0.450088)
			(layers "F.Cu" "F.Mask" "F.Paste")
			(net "GND")
		)
		(pad "AM54" smd circle
			(at 15.189962 -11.700002 180)
			(size 0.450088 0.450088)
			(layers "F.Cu" "F.Mask" "F.Paste")
			(net "PVDDIO_P1")
		)
		(pad "AM55" smd circle
			(at 16.130016 -11.700002 180)
			(size 0.450088 0.450088)
			(layers "F.Cu" "F.Mask" "F.Paste")
			(net "M_C_CPU1_SA_DQS_DN<9>")
		)
		(pad "AM56" smd circle
			(at 17.07007 -11.700002 180)
			(size 0.450088 0.450088)
			(layers "F.Cu" "F.Mask" "F.Paste")
			(net "M_C_CPU1_SA_DQS_DN<4>")
		)
		(pad "AM57" smd circle
			(at 18.010124 -11.700002 180)
			(size 0.450088 0.450088)
			(layers "F.Cu" "F.Mask" "F.Paste")
			(net "PVDDIO_P1")
		)
		(pad "AM58" smd circle
			(at 18.949924 -11.700002 180)
			(size 0.450088 0.450088)
			(layers "F.Cu" "F.Mask" "F.Paste")
			(net "M_D_CPU1_SA_DQS_DN<9>")
		)
		(pad "AM59" smd circle
			(at 19.889978 -11.700002 180)
			(size 0.450088 0.450088)
			(layers "F.Cu" "F.Mask" "F.Paste")
			(net "GND")
		)
		(pad "AM60" smd circle
			(at 20.830032 -11.700002 180)
			(size 0.450088 0.450088)
			(layers "F.Cu" "F.Mask" "F.Paste")
			(net "M_D_CPU1_SA_DQS_DN<4>")
		)
		(pad "AM61" smd circle
			(at 21.770086 -11.700002 180)
			(size 0.450088 0.450088)
			(layers "F.Cu" "F.Mask" "F.Paste")
			(net "GND")
		)
		(pad "AM62" smd circle
			(at 22.709886 -11.700002 180)
			(size 0.450088 0.450088)
			(layers "F.Cu" "F.Mask" "F.Paste")
			(net "M_B_CPU1_SA_DQS_DN<9>")
		)
		(pad "AM63" smd circle
			(at 23.64994 -11.700002 180)
			(size 0.450088 0.450088)
			(layers "F.Cu" "F.Mask" "F.Paste")
			(net "M_B_CPU1_SA_DQS_DN<4>")
		)
		(pad "AM64" smd circle
			(at 24.589994 -11.700002 180)
			(size 0.450088 0.450088)
			(layers "F.Cu" "F.Mask" "F.Paste")
			(net "PVDDIO_P1")
		)
		(pad "AM65" smd circle
			(at 25.530048 -11.700002 180)
			(size 0.450088 0.450088)
			(layers "F.Cu" "F.Mask" "F.Paste")
			(net "M_F_CPU1_SA_DQS_DN<9>")
		)
		(pad "AM66" smd circle
			(at 26.470102 -11.700002 180)
			(size 0.450088 0.450088)
			(layers "F.Cu" "F.Mask" "F.Paste")
			(net "GND")
		)
		(pad "AM67" smd circle
			(at 27.409902 -11.700002 180)
			(size 0.450088 0.450088)
			(layers "F.Cu" "F.Mask" "F.Paste")
			(net "M_F_CPU1_SA_DQS_DN<4>")
		)
		(pad "AM68" smd circle
			(at 28.349956 -11.700002 180)
			(size 0.450088 0.450088)
			(layers "F.Cu" "F.Mask" "F.Paste")
			(net "GND")
		)
		(pad "AM69" smd circle
			(at 29.29001 -11.700002 180)
			(size 0.450088 0.450088)
			(layers "F.Cu" "F.Mask" "F.Paste")
			(net "M_E_CPU1_SA_DQS_DN<9>")
		)
		(pad "AM70" smd circle
			(at 30.230064 -11.700002 180)
			(size 0.450088 0.450088)
			(layers "F.Cu" "F.Mask" "F.Paste")
			(net "M_E_CPU1_SA_DQS_DN<4>")
		)
		(pad "AM71" smd circle
			(at 31.170118 -11.700002 180)
			(size 0.450088 0.450088)
			(layers "F.Cu" "F.Mask" "F.Paste")
			(net "PVDDIO_P1")
		)
		(pad "AM72" smd circle
			(at 32.109918 -11.700002 180)
			(size 0.450088 0.450088)
			(layers "F.Cu" "F.Mask" "F.Paste")
			(net "M_A_CPU1_SA_DQS_DN<9>")
		)
		(pad "AM73" smd circle
			(at 33.049972 -11.700002 180)
			(size 0.450088 0.450088)
			(layers "F.Cu" "F.Mask" "F.Paste")
			(net "GND")
		)
		(pad "AM74" smd circle
			(at 33.990026 -11.700002 180)
			(size 0.450088 0.450088)
			(layers "F.Cu" "F.Mask" "F.Paste")
			(net "M_A_CPU1_SA_DQS_DN<4>")
		)
		(pad "AN1" smd circle
			(at -34.159952 -10.889996 180)
			(size 0.450088 0.450088)
			(layers "F.Cu" "F.Mask" "F.Paste")
			(net "GND")
		)
		(pad "AN2" smd circle
			(at -33.219898 -10.889996 180)
			(size 0.450088 0.450088)
			(layers "F.Cu" "F.Mask" "F.Paste")
			(net "M_G_CPU1_SA_CB<4>")
		)
		(pad "AN3" smd circle
			(at -32.280098 -10.889996 180)
			(size 0.450088 0.450088)
			(layers "F.Cu" "F.Mask" "F.Paste")
			(net "M_G_CPU1_SA_DQS_DP<9>")
		)
		(pad "AN4" smd circle
			(at -31.340044 -10.889996 180)
			(size 0.450088 0.450088)
			(layers "F.Cu" "F.Mask" "F.Paste")
			(net "GND")
		)
		(pad "AN5" smd circle
			(at -30.39999 -10.889996 180)
			(size 0.450088 0.450088)
			(layers "F.Cu" "F.Mask" "F.Paste")
			(net "M_K_CPU1_SA_CB<4>")
		)
		(pad "AN6" smd circle
			(at -29.459936 -10.889996 180)
			(size 0.450088 0.450088)
			(layers "F.Cu" "F.Mask" "F.Paste")
			(net "GND")
		)
		(pad "AN7" smd circle
			(at -28.519882 -10.889996 180)
			(size 0.450088 0.450088)
			(layers "F.Cu" "F.Mask" "F.Paste")
			(net "M_K_CPU1_SA_DQS_DP<9>")
		)
		(pad "AN8" smd circle
			(at -27.580082 -10.889996 180)
			(size 0.450088 0.450088)
			(layers "F.Cu" "F.Mask" "F.Paste")
			(net "GND")
		)
		(pad "AN9" smd circle
			(at -26.640028 -10.889996 180)
			(size 0.450088 0.450088)
			(layers "F.Cu" "F.Mask" "F.Paste")
			(net "M_L_CPU1_SA_CB<4>")
		)
		(pad "AN10" smd circle
			(at -25.699974 -10.889996 180)
			(size 0.450088 0.450088)
			(layers "F.Cu" "F.Mask" "F.Paste")
			(net "M_L_CPU1_SA_DQS_DP<9>")
		)
		(pad "AN11" smd circle
			(at -24.75992 -10.889996 180)
			(size 0.450088 0.450088)
			(layers "F.Cu" "F.Mask" "F.Paste")
			(net "GND")
		)
		(pad "AN12" smd circle
			(at -23.82012 -10.889996 180)
			(size 0.450088 0.450088)
			(layers "F.Cu" "F.Mask" "F.Paste")
			(net "M_H_CPU1_SA_CB<4>")
		)
		(pad "AN13" smd circle
			(at -22.880066 -10.889996 180)
			(size 0.450088 0.450088)
			(layers "F.Cu" "F.Mask" "F.Paste")
			(net "GND")
		)
		(pad "AN14" smd circle
			(at -21.940012 -10.889996 180)
			(size 0.450088 0.450088)
			(layers "F.Cu" "F.Mask" "F.Paste")
			(net "M_H_CPU1_SA_DQS_DP<9>")
		)
		(pad "AN15" smd circle
			(at -20.999958 -10.889996 180)
			(size 0.450088 0.450088)
			(layers "F.Cu" "F.Mask" "F.Paste")
			(net "GND")
		)
		(pad "AN16" smd circle
			(at -20.059904 -10.889996 180)
			(size 0.450088 0.450088)
			(layers "F.Cu" "F.Mask" "F.Paste")
			(net "M_J_CPU1_SA_CB<4>")
		)
		(pad "AN17" smd circle
			(at -19.120104 -10.889996 180)
			(size 0.450088 0.450088)
			(layers "F.Cu" "F.Mask" "F.Paste")
			(net "M_J_CPU1_SA_DQS_DP<9>")
		)
		(pad "AN18" smd circle
			(at -18.18005 -10.889996 180)
			(size 0.450088 0.450088)
			(layers "F.Cu" "F.Mask" "F.Paste")
			(net "GND")
		)
		(pad "AN19" smd circle
			(at -17.239996 -10.889996 180)
			(size 0.450088 0.450088)
			(layers "F.Cu" "F.Mask" "F.Paste")
			(net "M_I_CPU1_SA_CB<4>")
		)
		(pad "AN20" smd circle
			(at -16.299942 -10.889996 180)
			(size 0.450088 0.450088)
			(layers "F.Cu" "F.Mask" "F.Paste")
			(net "GND")
		)
		(pad "AN21" smd circle
			(at -15.359888 -10.889996 180)
			(size 0.450088 0.450088)
			(layers "F.Cu" "F.Mask" "F.Paste")
			(net "M_I_CPU1_SA_DQS_DP<9>")
		)
		(pad "AN22" smd circle
			(at -14.420088 -10.889996 180)
			(size 0.450088 0.450088)
			(layers "F.Cu" "F.Mask" "F.Paste")
			(net "GND")
		)
		(pad "AN23" smd circle
			(at -13.480034 -10.889996 180)
			(size 0.450088 0.450088)
			(layers "F.Cu" "F.Mask" "F.Paste")
			(net "GMI_CPU0_G1_CPU1_G3_TX_DN<13>")
		)
		(pad "AN24" smd circle
			(at -12.53998 -10.889996 180)
			(size 0.450088 0.450088)
			(layers "F.Cu" "F.Mask" "F.Paste")
			(net "GMI_CPU0_G1_CPU1_G3_TX_DP<13>")
		)
		(pad "AN25" smd circle
			(at -11.599926 -10.889996 180)
			(size 0.450088 0.450088)
			(layers "F.Cu" "F.Mask" "F.Paste")
			(net "GND")
		)
		(pad "AN26" smd circle
			(at -10.659872 -10.889996 180)
			(size 0.450088 0.450088)
			(layers "F.Cu" "F.Mask" "F.Paste")
			(net "GMI_CPU0_G1_CPU1_G3_TX_DN<10>")
		)
		(pad "AN27" smd circle
			(at -9.720072 -10.889996 180)
			(size 0.450088 0.450088)
			(layers "F.Cu" "F.Mask" "F.Paste")
			(net "GMI_CPU0_G1_CPU1_G3_TX_DP<10>")
		)
		(pad "AN28" smd circle
			(at -8.780018 -10.889996 180)
			(size 0.450088 0.450088)
			(layers "F.Cu" "F.Mask" "F.Paste")
			(net "GND")
		)
		(pad "AN29" smd circle
			(at -7.839964 -10.889996 180)
			(size 0.450088 0.450088)
			(layers "F.Cu" "F.Mask" "F.Paste")
			(net "GMI_CPU0_G1_CPU1_G3_TX_DN<7>")
		)
		(pad "AN30" smd circle
			(at -6.89991 -10.889996 180)
			(size 0.450088 0.450088)
			(layers "F.Cu" "F.Mask" "F.Paste")
			(net "GMI_CPU0_G1_CPU1_G3_TX_DP<7>")
		)
		(pad "AN31" smd circle
			(at -5.96011 -10.889996 180)
			(size 0.450088 0.450088)
			(layers "F.Cu" "F.Mask" "F.Paste")
			(net "GND")
		)
		(pad "AN32" smd circle
			(at -5.020056 -10.889996 180)
			(size 0.450088 0.450088)
			(layers "F.Cu" "F.Mask" "F.Paste")
			(net "GMI_CPU0_G1_CPU1_G3_TX_DN<4>")
		)
		(pad "AN33" smd circle
			(at -4.080002 -10.889996 180)
			(size 0.450088 0.450088)
			(layers "F.Cu" "F.Mask" "F.Paste")
			(net "GMI_CPU0_G1_CPU1_G3_TX_DP<4>")
		)
		(pad "AN34" smd circle
			(at -3.139948 -10.889996 180)
			(size 0.450088 0.450088)
			(layers "F.Cu" "F.Mask" "F.Paste")
			(net "GND")
		)
		(pad "AN35" smd circle
			(at -2.199894 -10.889996 180)
			(size 0.450088 0.450088)
			(layers "F.Cu" "F.Mask" "F.Paste")
			(net "GND")
		)
		(pad "AN36" smd circle
			(at -1.260094 -10.889996 180)
			(size 0.450088 0.450088)
			(layers "F.Cu" "F.Mask" "F.Paste")
			(net "GND")
		)
		(pad "AN40" smd circle
			(at 1.560068 -10.889996 180)
			(size 0.450088 0.450088)
			(layers "F.Cu" "F.Mask" "F.Paste")
			(net "GND")
		)
		(pad "AN41" smd circle
			(at 2.500122 -10.889996 180)
			(size 0.450088 0.450088)
			(layers "F.Cu" "F.Mask" "F.Paste")
			(net "GND")
		)
		(pad "AN42" smd circle
			(at 3.439922 -10.889996 180)
			(size 0.450088 0.450088)
			(layers "F.Cu" "F.Mask" "F.Paste")
			(net "GND")
		)
		(pad "AN43" smd circle
			(at 4.379976 -10.889996 180)
			(size 0.450088 0.450088)
			(layers "F.Cu" "F.Mask" "F.Paste")
			(net "P5E_CPU1_G1_TX_DP<4>")
		)
		(pad "AN44" smd circle
			(at 5.32003 -10.889996 180)
			(size 0.450088 0.450088)
			(layers "F.Cu" "F.Mask" "F.Paste")
			(net "P5E_CPU1_G1_TX_DN<4>")
		)
		(pad "AN45" smd circle
			(at 6.260084 -10.889996 180)
			(size 0.450088 0.450088)
			(layers "F.Cu" "F.Mask" "F.Paste")
			(net "GND")
		)
		(pad "AN46" smd circle
			(at 7.199884 -10.889996 180)
			(size 0.450088 0.450088)
			(layers "F.Cu" "F.Mask" "F.Paste")
			(net "P5E_CPU1_G1_TX_DP<7>")
		)
		(pad "AN47" smd circle
			(at 8.139938 -10.889996 180)
			(size 0.450088 0.450088)
			(layers "F.Cu" "F.Mask" "F.Paste")
			(net "P5E_CPU1_G1_TX_DN<7>")
		)
		(pad "AN48" smd circle
			(at 9.079992 -10.889996 180)
			(size 0.450088 0.450088)
			(layers "F.Cu" "F.Mask" "F.Paste")
			(net "GND")
		)
		(pad "AN49" smd circle
			(at 10.020046 -10.889996 180)
			(size 0.450088 0.450088)
			(layers "F.Cu" "F.Mask" "F.Paste")
			(net "P5E_CPU1_G1_TX_DP<10>")
		)
		(pad "AN50" smd circle
			(at 10.9601 -10.889996 180)
			(size 0.450088 0.450088)
			(layers "F.Cu" "F.Mask" "F.Paste")
			(net "P5E_CPU1_G1_TX_DN<10>")
		)
		(pad "AN51" smd circle
			(at 11.8999 -10.889996 180)
			(size 0.450088 0.450088)
			(layers "F.Cu" "F.Mask" "F.Paste")
			(net "GND")
		)
		(pad "AN52" smd circle
			(at 12.839954 -10.889996 180)
			(size 0.450088 0.450088)
			(layers "F.Cu" "F.Mask" "F.Paste")
			(net "P5E_CPU1_G1_TX_DP<13>")
		)
	)
)
